#ISCELL
  mstr_misc dns *
  *
#ISCELL
  pure_quanta quanta_title_block_c *
  *
#ISCELL
  standard offpage *
  page173_i1
#ISCELL
  standard offpage *
  page173_i10
#CELL
  pure_quanta q_cap *
  page173_i11
#CELL
  pure_quanta q_res *
  page173_i12
#ISCELL
  pure_quanta_power vcc_core *
  page173_i13
#CELL
  pure_quanta q_cap *
  page173_i14
#ISCELL
  pure_quanta_power universal_gnd *
  page173_i15
#ISCELL
  pure_quanta_power universal_gnd *
  page173_i16
#ISCELL
  pure_quanta_power universal_gnd *
  page173_i17
#CELL
  pure_quanta q_res *
  page173_i18
#CELL
  pure_quanta q_res *
  page173_i19
#ISCELL
  standard offpage *
  page173_i2
#ISCELL
  standard offpage *
  page173_i20
#CELL
  pure_quanta q_cap *
  page173_i21
#CELL
  pure_quanta q_res *
  page173_i22
#CELL
  pure_quanta q_cap *
  page173_i23
#CELL
  pure_quanta q_cap *
  page173_i24
#CELL
  pure_quanta q_cap *
  page173_i25
#ISCELL
  pure_quanta_power universal_gnd *
  page173_i26
#CELL
  pure_quanta q_res *
  page173_i27
#ISCELL
  pure_quanta_power universal_gnd *
  page173_i28
#CELL
  pure_quanta q_cap *
  page173_i29
#ISCELL
  pure_quanta_power universal_gnd *
  page173_i3
#ISCELL
  pure_quanta_power universal_gnd *
  page173_i30
#ISCELL
  standard offpage *
  page173_i31
#CELL
  pure_quanta q_res *
  page173_i32
#ISCELL
  standard offpage *
  page173_i33
#ISCELL
  pure_quanta_power universal_gnd *
  page173_i34
#ISCELL
  standard offpage *
  page173_i35
#CELL
  pure_quanta q_cap *
  page173_i36
#ISCELL
  pure_quanta_power universal_gnd *
  page173_i37
#CELL
  pure_quanta q_res *
  page173_i38
#ISCELL
  pure_quanta_power vcc_core *
  page173_i39
#CELL
  pure_quanta q_cap *
  page173_i4
#CELL
  pure_quanta q_cap *
  page173_i40
#CELL
  pure_quanta isl99390frztr5935 *
  page173_i41
#ISCELL
  pure_quanta_power universal_gnd *
  page173_i42
#CELL
  pure_quanta q_cap *
  page173_i43
#CELL
  pure_quanta q_cap *
  page173_i44
#CELL
  pure_quanta q_res *
  page173_i45
#CELL
  pure_quanta q_cap *
  page173_i46
#ISCELL
  standard offpage *
  page173_i47
#CELL
  pure_quanta q_res *
  page173_i48
#CELL
  pure_quanta q_cap *
  page173_i49
#ISCELL
  pure_quanta_power universal_gnd *
  page173_i5
#CELL
  pure_quanta q_cap *
  page173_i50
#CELL
  pure_quanta q_cap *
  page173_i51
#CELL
  pure_quanta q_cap *
  page173_i52
#CELL
  pure_quanta q_inductor4p_14 *
  page173_i53
#ISCELL
  standard offpage *
  page173_i54
#ISCELL
  pure_quanta_power universal_gnd *
  page173_i55
#CELL
  pure_quanta q_cap *
  page173_i56
#CELL
  pure_quanta q_cap *
  page173_i57
#ISCELL
  pure_quanta_power vcc_core *
  page173_i58
#CELL
  pure_quanta q_cap *
  page173_i59
#ISCELL
  standard offpage *
  page173_i6
#ISCELL
  pure_quanta_power universal_gnd *
  page173_i60
#CELL
  pure_quanta q_cap *
  page173_i61
#ISCELL
  pure_quanta_power vcc_core *
  page173_i62
#CELL
  pure_quanta q_capp *
  page173_i63
#CELL
  pure_quanta q_capp *
  page173_i64
#ISCELL
  pure_quanta_power universal_gnd *
  page173_i65
#CELL
  pure_quanta q_capp *
  page173_i66
#ISCELL
  pure_quanta_power vcc_core *
  page173_i67
#CELL
  pure_quanta q_cap *
  page173_i68
#CELL
  pure_quanta q_inductor4p_14 *
  page173_i69
#ISCELL
  standard offpage *
  page173_i7
#ISCELL
  pure_quanta_power universal_gnd *
  page173_i70
#ISCELL
  pure_quanta_power vcc_core *
  page173_i71
#CELL
  pure_quanta q_cap *
  page173_i72
#CELL
  pure_quanta q_capp *
  page173_i73
#CELL
  pure_quanta q_inductor *
  page173_i74
#ISCELL
  pure_quanta_power universal_gnd *
  page173_i75
#ISCELL
  pure_quanta_power universal_gnd *
  page173_i76
#CELL
  pure_quanta q_cap *
  page173_i77
#ISCELL
  pure_quanta_power vcc_core *
  page173_i78
#CELL
  pure_quanta q_cap *
  page173_i79
#CELL
  pure_quanta q_res *
  page173_i8
#CELL
  pure_quanta q_cap *
  page173_i80
#ISCELL
  pure_quanta_power universal_gnd *
  page173_i81
#CELL
  pure_quanta q_res *
  page173_i82
#CELL
  pure_quanta q_cap *
  page173_i83
#ISCELL
  pure_quanta_power vcc_core *
  page173_i84
#CELL
  pure_quanta q_cap *
  page173_i85
#CELL
  pure_quanta isl99390frztr5935 *
  page173_i86
#CELL
  pure_quanta q_cap *
  page173_i87
#CELL
  pure_quanta q_cap *
  page173_i88
#ISCELL
  pure_quanta_power universal_gnd *
  page173_i9
